(kicad_pcb
	(version 20260206)
	(generator "pcbnew")
	(generator_version "10.0")
	(general
		(thickness 1.6)
		(legacy_teardrops no)
	)
	(paper "A4")
	(title_block
		(title "Wiwynn_Tioga_Pass_MB.brd")
		(comment 1 "Tioga Pass / footprints 1701-1707 of 4770")
	)
	(layers
		(0 "F.Cu" signal "TOP")
		(4 "In1.Cu" signal "L2GND")
		(6 "In2.Cu" signal "L3")
		(8 "In3.Cu" signal "L4GND")
		(10 "In4.Cu" signal "L5")
		(12 "In5.Cu" signal "L6GND")
		(14 "In6.Cu" signal "L7VCC")
		(16 "In7.Cu" signal "L8VCC")
		(18 "In8.Cu" signal "L9GND")
		(20 "In9.Cu" signal "L10")
		(22 "In10.Cu" signal "L11GND")
		(24 "In11.Cu" signal "L12")
		(26 "In12.Cu" signal "L13GND")
		(2 "B.Cu" signal "BOTTOM")
		(9 "F.Adhes" user "F.Adhesive")
		(11 "B.Adhes" user "B.Adhesive")
		(13 "F.Paste" user "Package Geometry/Pastemask Top")
		(15 "B.Paste" user "Package Geometry/Pastemask Bottom")
		(5 "F.SilkS" user "Ref Des/Silkscreen Top")
		(7 "B.SilkS" user "Ref Des/Silkscreen Bottom")
		(1 "F.Mask" user "Board Geometry/Soldermask Top")
		(3 "B.Mask" user "Board Geometry/Soldermask Bottom")
		(17 "Dwgs.User" user "User.Drawings")
		(19 "Cmts.User" user "User.Comments")
		(21 "Eco1.User" user "User.Eco1")
		(23 "Eco2.User" user "User.Eco2")
		(25 "Edge.Cuts" user "Board Geometry/Outline")
		(27 "Margin" user)
		(31 "F.CrtYd" user "Package Geometry/Place Bound Top")
		(29 "B.CrtYd" user "Package Geometry/Place Bound Bottom")
		(35 "F.Fab" user "Ref Des/Assembly Top")
		(33 "B.Fab" user "Ref Des/Assembly Bottom")
	)
	(footprint ""
		(layer "F.Cu")
		(at 421.63619 -52.795932 -90)
		(property "Reference" "Q8E2"
			(at -1.98247 1.9685 0)
			(unlocked yes)
			(layer "F.SilkS")
			(effects
				(font
					(size 0.7874 0.5842)
					(thickness 0.1524)
				)
				(justify left)
			)
		)
		(property "Value" ""
			(at 0 0 270)
			(layer "F.Fab")
			(effects
				(font
					(size 1.27 1.27)
				)
			)
		)
		(duplicate_pad_numbers_are_jumpers no)
		(fp_line
			(start 0.9525 2.4765)
			(end 1.778 2.4765)
			(stroke
				(width 0.1524)
				(type default)
			)
			(layer "F.SilkS")
		)
		(fp_line
			(start 1.778 2.4765)
			(end 1.778 1.5875)
			(stroke
				(width 0.1524)
				(type default)
			)
			(layer "F.SilkS")
		)
		(fp_line
			(start 0.381 0.635)
			(end 0.381 1.27)
			(stroke
				(width 0.1524)
				(type default)
			)
			(layer "F.SilkS")
		)
		(fp_line
			(start 0.9525 -0.5715)
			(end 1.778 -0.5715)
			(stroke
				(width 0.1524)
				(type default)
			)
			(layer "F.SilkS")
		)
		(fp_line
			(start 1.778 -0.5715)
			(end 1.778 0.3175)
			(stroke
				(width 0.1524)
				(type default)
			)
			(layer "F.SilkS")
		)
		(fp_circle
			(center -0.636524 -0.863854)
			(end -0.636524 -0.990854)
			(stroke
				(width 0.254)
				(type default)
			)
			(fill no)
			(layer "F.SilkS")
		)
		(fp_poly
			(pts
				(xy 1.778 2.4765) (xy 0.381 2.4765) (xy 0.381 -0.5715) (xy 1.778 -0.5715)
			)
			(stroke
				(width 0)
				(type default)
			)
			(fill no)
			(layer "F.CrtYd")
		)
		(fp_line
			(start 0.381 2.4765)
			(end 1.778 2.4765)
			(stroke
				(width 0.1)
				(type default)
			)
			(layer "F.Fab")
		)
		(fp_line
			(start 1.778 2.4765)
			(end 1.778 -0.5715)
			(stroke
				(width 0.1)
				(type default)
			)
			(layer "F.Fab")
		)
		(fp_line
			(start 0.381 -0.5715)
			(end 0.381 2.4765)
			(stroke
				(width 0.1)
				(type default)
			)
			(layer "F.Fab")
		)
		(fp_line
			(start 1.778 -0.5715)
			(end 0.381 -0.5715)
			(stroke
				(width 0.1)
				(type default)
			)
			(layer "F.Fab")
		)
		(fp_circle
			(center -0.9525 -0.9271)
			(end -0.9525 -1.0541)
			(stroke
				(width 0.254)
				(type default)
			)
			(fill no)
			(layer "F.Fab")
		)
		(pad "1" smd rect
			(at 0 0 270)
			(size 1.143 0.508)
			(layers "F.Cu" "F.Mask" "F.Paste")
			(net "RST_RSMRST_DLY")
		)
		(pad "2" smd rect
			(at 0 1.905 270)
			(size 1.143 0.508)
			(layers "F.Cu" "F.Mask" "F.Paste")
			(net "GND")
		)
		(pad "3" smd rect
			(at 2.159 0.9525 270)
			(size 1.143 0.508)
			(layers "F.Cu" "F.Mask" "F.Paste")
			(net "IRQ_SML0_ALERT_N")
		)
	)
	(footprint ""
		(layer "F.Cu")
		(at 402.66874 -32.902652 -90)
		(property "Reference" "R2U33"
			(at 0 0 270)
			(layer "F.SilkS")
			(hide yes)
			(effects
				(font
					(size 1.27 1.27)
				)
			)
		)
		(property "Value" ""
			(at 0 0 270)
			(layer "F.Fab")
			(effects
				(font
					(size 1.27 1.27)
				)
			)
		)
		(duplicate_pad_numbers_are_jumpers no)
		(fp_poly
			(pts
				(xy -0.2794 -0.1016) (xy 0.2794 -0.1016) (xy 0.2794 0.9906) (xy -0.2794 0.9906)
			)
			(stroke
				(width 0)
				(type default)
			)
			(fill no)
			(layer "F.CrtYd")
		)
		(fp_line
			(start -0.2794 0.9906)
			(end 0.2794 0.9906)
			(stroke
				(width 0.1)
				(type default)
			)
			(layer "F.Fab")
		)
		(fp_line
			(start 0.2794 0.9906)
			(end 0.2794 -0.1016)
			(stroke
				(width 0.1)
				(type default)
			)
			(layer "F.Fab")
		)
		(fp_line
			(start -0.2794 -0.1016)
			(end -0.2794 0.9906)
			(stroke
				(width 0.1)
				(type default)
			)
			(layer "F.Fab")
		)
		(fp_line
			(start 0.2794 -0.1016)
			(end -0.2794 -0.1016)
			(stroke
				(width 0.1)
				(type default)
			)
			(layer "F.Fab")
		)
		(pad "1" smd rect
			(at 0 0 270)
			(size 0.508 0.508)
			(layers "F.Cu" "F.Mask" "F.Paste")
			(net "SMB_HOST_STBY_LVC3_SDA_R")
		)
		(pad "2" smd rect
			(at 0 0.889 270)
			(size 0.508 0.508)
			(layers "F.Cu" "F.Mask" "F.Paste")
			(net "SMB_HOST_STBY_LVC3_SDA")
		)
		(zone
			(layer "F.Cu")
			(hatch none 0.5)
			(connect_pads
				(clearance 0)
			)
			(min_thickness 0.25)
			(keepout
				(tracks not_allowed)
				(vias allowed)
				(pads allowed)
				(copperpour not_allowed)
				(footprints allowed)
			)
			(placement
				(enabled no)
				(sheetname "")
			)
			(fill
				(thermal_gap 0.5)
				(thermal_bridge_width 0.5)
				(island_removal_mode 0)
			)
			(polygon
				(pts
					(xy 402.03374 -33.156652) (xy 402.03374 -32.648652) (xy 402.41474 -32.648652) (xy 402.41474 -33.156652)
				)
			)
		)
		(zone
			(layer "F.Cu")
			(hatch none 0.5)
			(connect_pads
				(clearance 0)
			)
			(min_thickness 0.25)
			(keepout
				(tracks allowed)
				(vias not_allowed)
				(pads allowed)
				(copperpour not_allowed)
				(footprints allowed)
			)
			(placement
				(enabled no)
				(sheetname "")
			)
			(fill
				(thermal_gap 0.5)
				(thermal_bridge_width 0.5)
				(island_removal_mode 0)
			)
			(polygon
				(pts
					(xy 402.41474 -33.156652) (xy 402.41474 -32.648652) (xy 402.03374 -32.648652) (xy 402.03374 -33.156652)
				)
			)
		)
	)
	(footprint ""
		(layer "F.Cu")
		(at 432.51882 -129.2987 180)
		(property "Reference" "C8B5"
			(at 0 0 180)
			(layer "F.SilkS")
			(hide yes)
			(effects
				(font
					(size 1.27 1.27)
				)
			)
		)
		(property "Value" ""
			(at 0 0 180)
			(layer "F.Fab")
			(effects
				(font
					(size 1.27 1.27)
				)
			)
		)
		(duplicate_pad_numbers_are_jumpers no)
		(fp_poly
			(pts
				(xy 0.3048 -0.1016) (xy 0.3048 0.9906) (xy -0.3048 0.9906) (xy -0.3048 -0.1016)
			)
			(stroke
				(width 0)
				(type default)
			)
			(fill no)
			(layer "F.CrtYd")
		)
		(fp_line
			(start 0.3048 0.9906)
			(end 0.3048 -0.1016)
			(stroke
				(width 0.1)
				(type default)
			)
			(layer "F.Fab")
		)
		(fp_line
			(start 0.3048 -0.1016)
			(end -0.3048 -0.1016)
			(stroke
				(width 0.1)
				(type default)
			)
			(layer "F.Fab")
		)
		(fp_line
			(start -0.3048 0.9906)
			(end 0.3048 0.9906)
			(stroke
				(width 0.1)
				(type default)
			)
			(layer "F.Fab")
		)
		(fp_line
			(start -0.3048 -0.1016)
			(end -0.3048 0.9906)
			(stroke
				(width 0.1)
				(type default)
			)
			(layer "F.Fab")
		)
		(pad "1" smd rect
			(at 0 0 180)
			(size 0.508 0.508)
			(layers "F.Cu" "F.Mask" "F.Paste")
			(net "P5V_STBY")
		)
		(pad "2" smd rect
			(at 0 0.889 180)
			(size 0.508 0.508)
			(layers "F.Cu" "F.Mask" "F.Paste")
			(net "GND")
		)
		(zone
			(layer "F.Cu")
			(hatch none 0.5)
			(connect_pads
				(clearance 0)
			)
			(min_thickness 0.25)
			(keepout
				(tracks not_allowed)
				(vias allowed)
				(pads allowed)
				(copperpour not_allowed)
				(footprints allowed)
			)
			(placement
				(enabled no)
				(sheetname "")
			)
			(fill
				(thermal_gap 0.5)
				(thermal_bridge_width 0.5)
				(island_removal_mode 0)
			)
			(polygon
				(pts
					(xy 432.77282 -129.9337) (xy 432.26482 -129.9337) (xy 432.26482 -129.5527) (xy 432.77282 -129.5527)
				)
			)
		)
		(zone
			(layer "F.Cu")
			(hatch none 0.5)
			(connect_pads
				(clearance 0)
			)
			(min_thickness 0.25)
			(keepout
				(tracks allowed)
				(vias not_allowed)
				(pads allowed)
				(copperpour not_allowed)
				(footprints allowed)
			)
			(placement
				(enabled no)
				(sheetname "")
			)
			(fill
				(thermal_gap 0.5)
				(thermal_bridge_width 0.5)
				(island_removal_mode 0)
			)
			(polygon
				(pts
					(xy 432.77282 -129.5527) (xy 432.26482 -129.5527) (xy 432.26482 -129.9337) (xy 432.77282 -129.9337)
				)
			)
		)
	)
	(footprint ""
		(layer "F.Cu")
		(at 344.42654 -10.686796 180)
		(property "Reference" "RF16"
			(at -0.8382 -0.67818 180)
			(unlocked yes)
			(layer "F.SilkS")
			(effects
				(font
					(size 0.4064 0.254)
					(thickness 0.1524)
				)
				(justify left)
			)
		)
		(property "Value" ""
			(at 0 0 180)
			(layer "F.Fab")
			(effects
				(font
					(size 1.27 1.27)
				)
			)
		)
		(duplicate_pad_numbers_are_jumpers no)
		(fp_poly
			(pts
				(xy -0.2794 -0.1016) (xy 0.2794 -0.1016) (xy 0.2794 0.9906) (xy -0.2794 0.9906)
			)
			(stroke
				(width 0)
				(type default)
			)
			(fill no)
			(layer "F.CrtYd")
		)
		(fp_line
			(start 0.2794 0.9906)
			(end 0.2794 -0.1016)
			(stroke
				(width 0.1)
				(type default)
			)
			(layer "F.Fab")
		)
		(fp_line
			(start 0.2794 -0.1016)
			(end -0.2794 -0.1016)
			(stroke
				(width 0.1)
				(type default)
			)
			(layer "F.Fab")
		)
		(fp_line
			(start -0.2794 0.9906)
			(end 0.2794 0.9906)
			(stroke
				(width 0.1)
				(type default)
			)
			(layer "F.Fab")
		)
		(fp_line
			(start -0.2794 -0.1016)
			(end -0.2794 0.9906)
			(stroke
				(width 0.1)
				(type default)
			)
			(layer "F.Fab")
		)
		(pad "1" smd rect
			(at 0 0 180)
			(size 0.508 0.508)
			(layers "F.Cu" "F.Mask" "F.Paste")
			(net "VR_PVDDQ_ABC_AIREF2")
		)
		(pad "2" smd rect
			(at 0 0.889 180)
			(size 0.508 0.508)
			(layers "F.Cu" "F.Mask" "F.Paste")
			(net "ISENSE_PVDDQ_ABC_PH2_IMON")
		)
		(zone
			(layer "F.Cu")
			(hatch none 0.5)
			(connect_pads
				(clearance 0)
			)
			(min_thickness 0.25)
			(keepout
				(tracks not_allowed)
				(vias allowed)
				(pads allowed)
				(copperpour not_allowed)
				(footprints allowed)
			)
			(placement
				(enabled no)
				(sheetname "")
			)
			(fill
				(thermal_gap 0.5)
				(thermal_bridge_width 0.5)
				(island_removal_mode 0)
			)
			(polygon
				(pts
					(xy 344.68054 -11.321796) (xy 344.17254 -11.321796) (xy 344.17254 -10.940796) (xy 344.68054 -10.940796)
				)
			)
		)
		(zone
			(layer "F.Cu")
			(hatch none 0.5)
			(connect_pads
				(clearance 0)
			)
			(min_thickness 0.25)
			(keepout
				(tracks allowed)
				(vias not_allowed)
				(pads allowed)
				(copperpour not_allowed)
				(footprints allowed)
			)
			(placement
				(enabled no)
				(sheetname "")
			)
			(fill
				(thermal_gap 0.5)
				(thermal_bridge_width 0.5)
				(island_removal_mode 0)
			)
			(polygon
				(pts
					(xy 344.68054 -10.940796) (xy 344.17254 -10.940796) (xy 344.17254 -11.321796) (xy 344.68054 -11.321796)
				)
			)
		)
	)
	(footprint ""
		(layer "F.Cu")
		(at 189.3316 -71.1454 180)
		(property "Reference" "CF5"
			(at 0 0 180)
			(layer "F.SilkS")
			(hide yes)
			(effects
				(font
					(size 1.27 1.27)
				)
			)
		)
		(property "Value" "*"
			(at 1.1811 -2.8194 180)
			(unlocked yes)
			(layer "F.Fab")
			(hide yes)
			(effects
				(font
					(size 1.27 1.016)
					(thickness 0.1524)
				)
			)
		)
		(property "Device Type" "SC22P50V2JN-4GP_SMD-BCG-SC22P5A"
			(at 1.1811 -4.3434 180)
			(unlocked yes)
			(layer "F.Fab")
			(hide yes)
			(effects
				(font
					(size 1.27 1.016)
					(thickness 0.1524)
				)
			)
		)
		(duplicate_pad_numbers_are_jumpers no)
		(fp_rect
			(start -0.4318 0.9525)
			(end 0.4318 -0.9525)
			(stroke
				(width 0)
				(type default)
			)
			(fill no)
			(layer "F.CrtYd")
		)
		(fp_rect
			(start -0.4318 0.9525)
			(end 0.4318 -0.9525)
			(stroke
				(width 0)
				(type default)
			)
			(fill no)
			(layer "F.Fab")
		)
		(pad "1" smd custom
			(at 0 -0.4445 180)
			(size 0.1524 0.1524)
			(layers "F.Cu" "F.Mask" "F.Paste")
			(net "VR_PVCCIN_CPU0_AIREF5")
			(options
				(clearance outline)
				(anchor circle)
			)
			(primitives
				(gr_poly
					(pts
						(arc
							(start 0.3048 -0.2032)
							(mid 0.275042 -0.275042)
							(end 0.2032 -0.3048)
						)
						(arc
							(start -0.2032 -0.3048)
							(mid -0.275042 -0.275042)
							(end -0.3048 -0.2032)
						)
						(arc
							(start -0.3048 0.2032)
							(mid -0.275042 0.275042)
							(end -0.2032 0.3048)
						)
						(arc
							(start 0.2032 0.3048)
							(mid 0.275042 0.275042)
							(end 0.3048 0.2032)
						)
					)
					(width 0)
					(fill yes)
				)
			)
		)
		(pad "2" smd custom
			(at 0 0.4445 180)
			(size 0.1524 0.1524)
			(layers "F.Cu" "F.Mask" "F.Paste")
			(net "ISENSE_PVCCIN_CPU0_PH5_IMON")
			(options
				(clearance outline)
				(anchor circle)
			)
			(primitives
				(gr_poly
					(pts
						(arc
							(start 0.3048 -0.2032)
							(mid 0.275042 -0.275042)
							(end 0.2032 -0.3048)
						)
						(arc
							(start -0.2032 -0.3048)
							(mid -0.275042 -0.275042)
							(end -0.3048 -0.2032)
						)
						(arc
							(start -0.3048 0.2032)
							(mid -0.275042 0.275042)
							(end -0.2032 0.3048)
						)
						(arc
							(start 0.2032 0.3048)
							(mid 0.275042 0.275042)
							(end 0.3048 0.2032)
						)
					)
					(width 0)
					(fill yes)
				)
			)
		)
	)
	(footprint ""
		(layer "F.Cu")
		(at 29.83865 -41.8592 180)
		(property "Reference" "C1E20"
			(at 0 0 180)
			(layer "F.SilkS")
			(hide yes)
			(effects
				(font
					(size 1.27 1.27)
				)
			)
		)
		(property "Value" ""
			(at 0 0 180)
			(layer "F.Fab")
			(effects
				(font
					(size 1.27 1.27)
				)
			)
		)
		(duplicate_pad_numbers_are_jumpers no)
		(fp_rect
			(start 0.3048 -0.1016)
			(end -0.3048 0.9906)
			(stroke
				(width 0)
				(type default)
			)
			(fill no)
			(layer "F.CrtYd")
		)
		(fp_line
			(start 0.3048 0.9906)
			(end 0.3048 -0.1016)
			(stroke
				(width 0.1)
				(type default)
			)
			(layer "F.Fab")
		)
		(fp_line
			(start 0.3048 -0.1016)
			(end -0.3048 -0.1016)
			(stroke
				(width 0.1)
				(type default)
			)
			(layer "F.Fab")
		)
		(fp_line
			(start -0.3048 0.9906)
			(end 0.3048 0.9906)
			(stroke
				(width 0.1)
				(type default)
			)
			(layer "F.Fab")
		)
		(fp_line
			(start -0.3048 -0.1016)
			(end -0.3048 0.9906)
			(stroke
				(width 0.1)
				(type default)
			)
			(layer "F.Fab")
		)
		(pad "1" smd rect
			(at 0 0 180)
			(size 0.508 0.508)
			(layers "F.Cu" "F.Mask" "F.Paste")
			(net "P12V_FAN")
		)
		(pad "2" smd rect
			(at 0 0.889 180)
			(size 0.508 0.508)
			(layers "F.Cu" "F.Mask" "F.Paste")
			(net "GND")
		)
		(zone
			(layer "F.Cu")
			(hatch none 0.5)
			(connect_pads
				(clearance 0)
			)
			(min_thickness 0.25)
			(keepout
				(tracks allowed)
				(vias not_allowed)
				(pads allowed)
				(copperpour not_allowed)
				(footprints allowed)
			)
			(placement
				(enabled no)
				(sheetname "")
			)
			(fill
				(thermal_gap 0.5)
				(thermal_bridge_width 0.5)
				(island_removal_mode 0)
			)
			(polygon
				(pts
					(xy 29.58465 -42.1132) (xy 30.09265 -42.1132) (xy 30.09265 -42.4942) (xy 29.58465 -42.4942)
				)
			)
		)
		(zone
			(layer "F.Cu")
			(hatch none 0.5)
			(connect_pads
				(clearance 0)
			)
			(min_thickness 0.25)
			(keepout
				(tracks not_allowed)
				(vias allowed)
				(pads allowed)
				(copperpour not_allowed)
				(footprints allowed)
			)
			(placement
				(enabled no)
				(sheetname "")
			)
			(fill
				(thermal_gap 0.5)
				(thermal_bridge_width 0.5)
				(island_removal_mode 0)
			)
			(polygon
				(pts
					(xy 29.58465 -42.1132) (xy 30.09265 -42.1132) (xy 30.09265 -42.4942) (xy 29.58465 -42.4942)
				)
			)
		)
	)
	(footprint ""
		(layer "F.Cu")
		(at 451.739 -131.2418 -90)
		(property "Reference" "C9B2"
			(at 0 0 270)
			(layer "F.SilkS")
			(hide yes)
			(effects
				(font
					(size 1.27 1.27)
				)
			)
		)
		(property "Value" ""
			(at 0 0 270)
			(layer "F.Fab")
			(effects
				(font
					(size 1.27 1.27)
				)
			)
		)
		(duplicate_pad_numbers_are_jumpers no)
		(fp_poly
			(pts
				(xy -0.7239 -0.2159) (xy 0.7239 -0.2159) (xy 0.7239 1.9939) (xy -0.7239 1.9939)
			)
			(stroke
				(width 0)
				(type default)
			)
			(fill no)
			(layer "F.CrtYd")
		)
		(fp_line
			(start -0.7239 1.9939)
			(end 0.7239 1.9939)
			(stroke
				(width 0.1)
				(type default)
			)
			(layer "F.Fab")
		)
		(fp_line
			(start 0.7239 1.9939)
			(end 0.7239 -0.2159)
			(stroke
				(width 0.1)
				(type default)
			)
			(layer "F.Fab")
		)
		(fp_line
			(start -0.7239 -0.2159)
			(end -0.7239 1.9939)
			(stroke
				(width 0.1)
				(type default)
			)
			(layer "F.Fab")
		)
		(fp_line
			(start 0.7239 -0.2159)
			(end -0.7239 -0.2159)
			(stroke
				(width 0.1)
				(type default)
			)
			(layer "F.Fab")
		)
		(pad "1" smd rect
			(at 0 0 270)
			(size 1.27 1.016)
			(layers "F.Cu" "F.Mask" "F.Paste")
			(net "P12V_HDD_SATA")
		)
		(pad "2" smd rect
			(at 0 1.778 270)
			(size 1.27 1.016)
			(layers "F.Cu" "F.Mask" "F.Paste")
			(net "GND")
		)
		(zone
			(layer "F.Cu")
			(hatch none 0.5)
			(connect_pads
				(clearance 0)
			)
			(min_thickness 0.25)
			(keepout
				(tracks not_allowed)
				(vias allowed)
				(pads allowed)
				(copperpour not_allowed)
				(footprints allowed)
			)
			(placement
				(enabled no)
				(sheetname "")
			)
			(fill
				(thermal_gap 0.5)
				(thermal_bridge_width 0.5)
				(island_removal_mode 0)
			)
			(polygon
				(pts
					(xy 451.231 -131.8768) (xy 451.231 -130.6068) (xy 450.469 -130.6068) (xy 450.469 -131.8768)
				)
			)
		)
	)
)
